(kicad_pcb
	(version 20260206)
	(generator "pcbnew")
	(generator_version "10.0")
	(general
		(thickness 1.6)
		(legacy_teardrops no)
	)
	(paper "A4")
	(title_block
		(title "01162023_DA0F0TEBIF0_F0T_Expander_BD_F_brd_V02_OCP.brd")
		(comment 1 "Grand Teton / footprints 2729-2734 of 9728")
	)
	(layers
		(0 "F.Cu" signal "TOP")
		(4 "In1.Cu" signal "GND")
		(6 "In2.Cu" signal "VCC")
		(8 "In3.Cu" signal "VCC1")
		(10 "In4.Cu" signal "GND1")
		(12 "In5.Cu" signal "IN1")
		(14 "In6.Cu" signal "GND2")
		(16 "In7.Cu" signal "IN2")
		(18 "In8.Cu" signal "GND3")
		(20 "In9.Cu" signal "IN3")
		(22 "In10.Cu" signal "GND4")
		(24 "In11.Cu" signal "IN4")
		(26 "In12.Cu" signal "GND5")
		(28 "In13.Cu" signal "IN5")
		(30 "In14.Cu" signal "GND6")
		(32 "In15.Cu" signal "IN6")
		(34 "In16.Cu" signal "GND7")
		(2 "B.Cu" signal "BOTTOM")
		(9 "F.Adhes" user "F.Adhesive")
		(11 "B.Adhes" user "B.Adhesive")
		(13 "F.Paste" user "Package Geometry/Pastemask Top")
		(15 "B.Paste" user "Package Geometry/Pastemask Bottom")
		(5 "F.SilkS" user "Ref Des/Silkscreen Top")
		(7 "B.SilkS" user "Ref Des/Silkscreen Bottom")
		(1 "F.Mask" user "Board Geometry/Soldermask Top")
		(3 "B.Mask" user "Board Geometry/Soldermask Bottom")
		(17 "Dwgs.User" user "User.Drawings")
		(19 "Cmts.User" user "User.Comments")
		(21 "Eco1.User" user "User.Eco1")
		(23 "Eco2.User" user "User.Eco2")
		(25 "Edge.Cuts" user "Board Geometry/Outline")
		(27 "Margin" user)
		(31 "F.CrtYd" user "Package Geometry/Place Bound Top")
		(29 "B.CrtYd" user "Package Geometry/Place Bound Bottom")
		(35 "F.Fab" user "Ref Des/Assembly Top")
		(33 "B.Fab" user "Ref Des/Assembly Bottom")
	)
	(footprint ""
		(layer "F.Cu")
		(at 140.074142 -174.881286 180)
		(property "Reference" "R1099"
			(at 0 0 180)
			(layer "F.SilkS")
			(hide yes)
			(effects
				(font
					(size 1.27 1.27)
				)
			)
		)
		(property "Value" ""
			(at 0 0 180)
			(layer "F.Fab")
			(effects
				(font
					(size 1.27 1.27)
				)
			)
		)
		(duplicate_pad_numbers_are_jumpers no)
		(fp_line
			(start 0.7874 0.4064)
			(end -0.7874 0.4064)
			(stroke
				(width 0.1524)
				(type default)
			)
			(layer "F.SilkS")
		)
		(fp_line
			(start 0.67945 0.3048)
			(end 0.120396 0.3048)
			(stroke
				(width 0.1)
				(type default)
			)
			(layer "F.Fab")
		)
		(fp_line
			(start 0.67945 -0.3048)
			(end 0.67945 0.3048)
			(stroke
				(width 0.1)
				(type default)
			)
			(layer "F.Fab")
		)
		(fp_line
			(start 0.12065 -0.2794)
			(end 0.12065 -0.3048)
			(stroke
				(width 0.1)
				(type default)
			)
			(layer "F.Fab")
		)
		(fp_line
			(start 0.12065 -0.3048)
			(end 0.67945 -0.3048)
			(stroke
				(width 0.1)
				(type default)
			)
			(layer "F.Fab")
		)
		(fp_line
			(start 0.120396 0.3048)
			(end 0.120396 0.2794)
			(stroke
				(width 0.1)
				(type default)
			)
			(layer "F.Fab")
		)
		(fp_line
			(start 0.120396 0.2794)
			(end -0.12065 0.2794)
			(stroke
				(width 0.1)
				(type default)
			)
			(layer "F.Fab")
		)
		(fp_line
			(start -0.12065 0.3048)
			(end -0.67945 0.3048)
			(stroke
				(width 0.1)
				(type default)
			)
			(layer "F.Fab")
		)
		(fp_line
			(start -0.12065 0.2794)
			(end -0.12065 0.3048)
			(stroke
				(width 0.1)
				(type default)
			)
			(layer "F.Fab")
		)
		(fp_line
			(start -0.12065 -0.2794)
			(end 0.12065 -0.2794)
			(stroke
				(width 0.1)
				(type default)
			)
			(layer "F.Fab")
		)
		(fp_line
			(start -0.12065 -0.305054)
			(end -0.12065 -0.2794)
			(stroke
				(width 0.1)
				(type default)
			)
			(layer "F.Fab")
		)
		(fp_line
			(start -0.67945 0.3048)
			(end -0.67945 -0.305054)
			(stroke
				(width 0.1)
				(type default)
			)
			(layer "F.Fab")
		)
		(fp_line
			(start -0.67945 -0.305054)
			(end -0.12065 -0.305054)
			(stroke
				(width 0.1)
				(type default)
			)
			(layer "F.Fab")
		)
		(pad "1" smd circle
			(at -0.40005 0 180)
			(size 0 0)
			(layers "F.Cu" "F.Mask" "F.Paste")
			(net "CLK_100M_DB2000QL_NIC2_R_DN")
		)
		(pad "2" smd circle
			(at 0.40005 0 180)
			(size 0 0)
			(layers "F.Cu" "F.Mask" "F.Paste")
			(net "CLK_100M_DB2000QL_NIC2_DN")
		)
	)
	(footprint ""
		(layer "F.Cu")
		(at 31.454344 -250.070874 -90)
		(property "Reference" "R1156"
			(at 0 0 270)
			(layer "F.SilkS")
			(hide yes)
			(effects
				(font
					(size 1.27 1.27)
				)
			)
		)
		(property "Value" ""
			(at 0 0 270)
			(layer "F.Fab")
			(effects
				(font
					(size 1.27 1.27)
				)
			)
		)
		(duplicate_pad_numbers_are_jumpers no)
		(fp_line
			(start -0.7874 0.4064)
			(end -0.7874 -0.4064)
			(stroke
				(width 0.1524)
				(type default)
			)
			(layer "F.SilkS")
		)
		(fp_line
			(start 0.7874 0.4064)
			(end -0.7874 0.4064)
			(stroke
				(width 0.1524)
				(type default)
			)
			(layer "F.SilkS")
		)
		(fp_line
			(start -0.7874 -0.4064)
			(end 0.7874 -0.4064)
			(stroke
				(width 0.1524)
				(type default)
			)
			(layer "F.SilkS")
		)
		(fp_line
			(start 0.7874 -0.4064)
			(end 0.7874 0.4064)
			(stroke
				(width 0.1524)
				(type default)
			)
			(layer "F.SilkS")
		)
		(fp_line
			(start -0.67945 0.3048)
			(end -0.67945 -0.305054)
			(stroke
				(width 0.1)
				(type default)
			)
			(layer "F.Fab")
		)
		(fp_line
			(start -0.12065 0.3048)
			(end -0.67945 0.3048)
			(stroke
				(width 0.1)
				(type default)
			)
			(layer "F.Fab")
		)
		(fp_line
			(start 0.120396 0.3048)
			(end 0.120396 0.2794)
			(stroke
				(width 0.1)
				(type default)
			)
			(layer "F.Fab")
		)
		(fp_line
			(start 0.67945 0.3048)
			(end 0.120396 0.3048)
			(stroke
				(width 0.1)
				(type default)
			)
			(layer "F.Fab")
		)
		(fp_line
			(start -0.12065 0.2794)
			(end -0.12065 0.3048)
			(stroke
				(width 0.1)
				(type default)
			)
			(layer "F.Fab")
		)
		(fp_line
			(start 0.120396 0.2794)
			(end -0.12065 0.2794)
			(stroke
				(width 0.1)
				(type default)
			)
			(layer "F.Fab")
		)
		(fp_line
			(start -0.12065 -0.2794)
			(end 0.12065 -0.2794)
			(stroke
				(width 0.1)
				(type default)
			)
			(layer "F.Fab")
		)
		(fp_line
			(start 0.12065 -0.2794)
			(end 0.12065 -0.3048)
			(stroke
				(width 0.1)
				(type default)
			)
			(layer "F.Fab")
		)
		(fp_line
			(start 0.12065 -0.3048)
			(end 0.67945 -0.3048)
			(stroke
				(width 0.1)
				(type default)
			)
			(layer "F.Fab")
		)
		(fp_line
			(start 0.67945 -0.3048)
			(end 0.67945 0.3048)
			(stroke
				(width 0.1)
				(type default)
			)
			(layer "F.Fab")
		)
		(fp_line
			(start -0.67945 -0.305054)
			(end -0.12065 -0.305054)
			(stroke
				(width 0.1)
				(type default)
			)
			(layer "F.Fab")
		)
		(fp_line
			(start -0.12065 -0.305054)
			(end -0.12065 -0.2794)
			(stroke
				(width 0.1)
				(type default)
			)
			(layer "F.Fab")
		)
		(pad "1" smd circle
			(at -0.40005 0 270)
			(size 0 0)
			(layers "F.Cu" "F.Mask" "F.Paste")
			(net "PEX0_MODE_SEL4")
		)
		(pad "2" smd circle
			(at 0.40005 0 270)
			(size 0 0)
			(layers "F.Cu" "F.Mask" "F.Paste")
			(net "P1V8_PEX")
		)
	)
	(footprint ""
		(layer "F.Cu")
		(at 106.29265 -7.742682)
		(property "Reference" "R1658"
			(at 0 0 0)
			(layer "F.SilkS")
			(hide yes)
			(effects
				(font
					(size 1.27 1.27)
				)
			)
		)
		(property "Value" ""
			(at 0 0 0)
			(layer "F.Fab")
			(effects
				(font
					(size 1.27 1.27)
				)
			)
		)
		(duplicate_pad_numbers_are_jumpers no)
		(fp_line
			(start -0.7874 -0.4064)
			(end 0.7874 -0.4064)
			(stroke
				(width 0.1524)
				(type default)
			)
			(layer "F.SilkS")
		)
		(fp_line
			(start -0.7874 0.4064)
			(end -0.7874 -0.4064)
			(stroke
				(width 0.1524)
				(type default)
			)
			(layer "F.SilkS")
		)
		(fp_line
			(start 0.7874 -0.4064)
			(end 0.7874 0.4064)
			(stroke
				(width 0.1524)
				(type default)
			)
			(layer "F.SilkS")
		)
		(fp_line
			(start 0.7874 0.4064)
			(end -0.7874 0.4064)
			(stroke
				(width 0.1524)
				(type default)
			)
			(layer "F.SilkS")
		)
		(fp_line
			(start -0.67945 -0.305054)
			(end -0.12065 -0.305054)
			(stroke
				(width 0.1)
				(type default)
			)
			(layer "F.Fab")
		)
		(fp_line
			(start -0.67945 0.3048)
			(end -0.67945 -0.305054)
			(stroke
				(width 0.1)
				(type default)
			)
			(layer "F.Fab")
		)
		(fp_line
			(start -0.12065 -0.305054)
			(end -0.12065 -0.2794)
			(stroke
				(width 0.1)
				(type default)
			)
			(layer "F.Fab")
		)
		(fp_line
			(start -0.12065 -0.2794)
			(end 0.12065 -0.2794)
			(stroke
				(width 0.1)
				(type default)
			)
			(layer "F.Fab")
		)
		(fp_line
			(start -0.12065 0.2794)
			(end -0.12065 0.3048)
			(stroke
				(width 0.1)
				(type default)
			)
			(layer "F.Fab")
		)
		(fp_line
			(start -0.12065 0.3048)
			(end -0.67945 0.3048)
			(stroke
				(width 0.1)
				(type default)
			)
			(layer "F.Fab")
		)
		(fp_line
			(start 0.120396 0.2794)
			(end -0.12065 0.2794)
			(stroke
				(width 0.1)
				(type default)
			)
			(layer "F.Fab")
		)
		(fp_line
			(start 0.120396 0.3048)
			(end 0.120396 0.2794)
			(stroke
				(width 0.1)
				(type default)
			)
			(layer "F.Fab")
		)
		(fp_line
			(start 0.12065 -0.3048)
			(end 0.67945 -0.3048)
			(stroke
				(width 0.1)
				(type default)
			)
			(layer "F.Fab")
		)
		(fp_line
			(start 0.12065 -0.2794)
			(end 0.12065 -0.3048)
			(stroke
				(width 0.1)
				(type default)
			)
			(layer "F.Fab")
		)
		(fp_line
			(start 0.67945 -0.3048)
			(end 0.67945 0.3048)
			(stroke
				(width 0.1)
				(type default)
			)
			(layer "F.Fab")
		)
		(fp_line
			(start 0.67945 0.3048)
			(end 0.120396 0.3048)
			(stroke
				(width 0.1)
				(type default)
			)
			(layer "F.Fab")
		)
		(pad "1" smd circle
			(at -0.40005 0)
			(size 0 0)
			(layers "F.Cu" "F.Mask" "F.Paste")
			(net "SMB_BIC_I2C9_MUX0_SSD3_R_SCL")
		)
		(pad "2" smd circle
			(at 0.40005 0)
			(size 0 0)
			(layers "F.Cu" "F.Mask" "F.Paste")
			(net "SMB_ISO_SSD3_SCL")
		)
	)
	(footprint ""
		(layer "F.Cu")
		(at 183.301386 -55.78475 -90)
		(property "Reference" "PD31"
			(at 4.01955 2.147316 90)
			(unlocked yes)
			(layer "F.SilkS")
			(effects
				(font
					(size 0.7874 0.5842)
					(thickness 0.1524)
				)
				(justify left)
			)
		)
		(property "Value" ""
			(at 0 0 270)
			(layer "F.Fab")
			(effects
				(font
					(size 1.27 1.27)
				)
			)
		)
		(duplicate_pad_numbers_are_jumpers no)
		(fp_line
			(start -3.400044 1.459992)
			(end -3.400044 -1.459992)
			(stroke
				(width 0.1524)
				(type default)
			)
			(layer "F.SilkS")
		)
		(fp_line
			(start 4.107942 1.459992)
			(end -3.400044 1.459992)
			(stroke
				(width 0.1524)
				(type default)
			)
			(layer "F.SilkS")
		)
		(fp_line
			(start -3.400044 -1.459992)
			(end 4.107942 -1.459992)
			(stroke
				(width 0.1524)
				(type default)
			)
			(layer "F.SilkS")
		)
		(fp_line
			(start 4.107942 -1.459992)
			(end 4.107942 1.459992)
			(stroke
				(width 0.1524)
				(type default)
			)
			(layer "F.SilkS")
		)
		(fp_poly
			(pts
				(xy 4.107942 -1.459992) (xy 4.107942 1.459992) (xy 3.308096 1.459992) (xy 3.308096 -1.459992)
			)
			(stroke
				(width 0)
				(type default)
			)
			(fill yes)
			(layer "F.SilkS")
		)
		(fp_line
			(start -2.29997 1.459992)
			(end -2.29997 -1.459992)
			(stroke
				(width 0.1)
				(type default)
			)
			(layer "F.Fab")
		)
		(fp_line
			(start 2.29997 1.459992)
			(end -2.29997 1.459992)
			(stroke
				(width 0.1)
				(type default)
			)
			(layer "F.Fab")
		)
		(fp_line
			(start -2.29997 -1.459992)
			(end 2.29997 -1.459992)
			(stroke
				(width 0.1)
				(type default)
			)
			(layer "F.Fab")
		)
		(fp_line
			(start 2.29997 -1.459992)
			(end 2.29997 1.459992)
			(stroke
				(width 0.1)
				(type default)
			)
			(layer "F.Fab")
		)
		(fp_text user "-"
			(at 5.4102 0.29845 90)
			(unlocked yes)
			(layer "F.SilkS")
			(effects
				(font
					(size 1.905 1.4224)
					(thickness 0.1524)
				)
				(justify left)
			)
		)
		(fp_text user "+"
			(at -4.7752 -0.12065 270)
			(unlocked yes)
			(layer "F.SilkS")
			(effects
				(font
					(size 1.905 1.4224)
					(thickness 0.1524)
				)
				(justify left)
			)
		)
		(fp_text user "-"
			(at 5.4102 0.29845 90)
			(unlocked yes)
			(layer "F.Fab")
			(effects
				(font
					(size 1.905 1.4224)
					(thickness 0.1524)
				)
				(justify left)
			)
		)
		(fp_text user "+"
			(at -4.7752 -0.12065 270)
			(unlocked yes)
			(layer "F.Fab")
			(effects
				(font
					(size 1.905 1.4224)
					(thickness 0.1524)
				)
				(justify left)
			)
		)
		(pad "A" smd rect
			(at -1.999996 0)
			(size 1.7018 2.5146)
			(layers "F.Cu" "F.Mask" "F.Paste")
			(net "GND")
		)
		(pad "C" smd rect
			(at 1.999996 0)
			(size 1.7018 2.5146)
			(layers "F.Cu" "F.Mask" "F.Paste")
			(net "P12V_SSD6_R")
		)
	)
	(footprint ""
		(layer "F.Cu")
		(at 443.800484 -450.437758 90)
		(property "Reference" "J52"
			(at -3.5052 -5.552948 90)
			(unlocked yes)
			(layer "F.SilkS")
			(effects
				(font
					(size 0.7874 0.5842)
					(thickness 0.1524)
				)
				(justify left)
			)
		)
		(property "Value" ""
			(at 0 0 90)
			(layer "F.Fab")
			(effects
				(font
					(size 1.27 1.27)
				)
			)
		)
		(duplicate_pad_numbers_are_jumpers no)
		(fp_line
			(start 3.330702 -4.771136)
			(end 0 4.011168)
			(stroke
				(width 0.1524)
				(type default)
			)
			(layer "F.SilkS")
		)
		(fp_line
			(start -3.330702 -4.771136)
			(end 3.330702 -4.771136)
			(stroke
				(width 0.1524)
				(type default)
			)
			(layer "F.SilkS")
		)
		(fp_line
			(start 0 4.011168)
			(end -3.330702 -4.771136)
			(stroke
				(width 0.1524)
				(type default)
			)
			(layer "F.SilkS")
		)
		(fp_line
			(start 3.330702 -4.771136)
			(end 0 4.011168)
			(stroke
				(width 0.1)
				(type default)
			)
			(layer "F.Fab")
		)
		(fp_line
			(start -3.330702 -4.771136)
			(end 3.330702 -4.771136)
			(stroke
				(width 0.1)
				(type default)
			)
			(layer "F.Fab")
		)
		(fp_line
			(start 0 4.011168)
			(end -3.330702 -4.771136)
			(stroke
				(width 0.1)
				(type default)
			)
			(layer "F.Fab")
		)
		(pad "1" thru_hole circle
			(at 0 0 90)
			(size 2.159 2.159)
			(drill 1.7018)
			(layers "*.Cu" "*.Mask")
			(remove_unused_layers no)
			(net "COUPON_GND1")
			(clearance 0.0254)
			(thermal_gap 0.0254)
		)
		(pad "2" thru_hole circle
			(at -1.27 -3.348736 90)
			(size 2.159 2.159)
			(drill 1.7018)
			(layers "*.Cu" "*.Mask")
			(remove_unused_layers no)
			(net "TDR_SE_50_OHM_IN6")
			(clearance 0.0254)
			(thermal_gap 0.0254)
		)
		(pad "3" thru_hole circle
			(at 1.27 -3.348736 90)
			(size 2.159 2.159)
			(drill 1.7018)
			(layers "*.Cu" "*.Mask")
			(remove_unused_layers no)
			(net "TDR_SE_50_OHM_IN6")
			(clearance 0.0254)
			(thermal_gap 0.0254)
		)
	)
	(footprint ""
		(layer "F.Cu")
		(at 355.163628 -244.976142)
		(property "Reference" "J55"
			(at -1.4224 -4.562348 0)
			(unlocked yes)
			(layer "F.SilkS")
			(effects
				(font
					(size 0.7874 0.5842)
					(thickness 0.1524)
				)
				(justify left)
			)
		)
		(property "Value" ""
			(at 0 0 0)
			(layer "F.Fab")
			(effects
				(font
					(size 1.27 1.27)
				)
			)
		)
		(duplicate_pad_numbers_are_jumpers no)
		(fp_line
			(start -1.27 -3.81)
			(end 1.27 -3.81)
			(stroke
				(width 0.1524)
				(type default)
			)
			(layer "F.SilkS")
		)
		(fp_line
			(start -1.27 -0.7747)
			(end -1.27 -3.81)
			(stroke
				(width 0.1524)
				(type default)
			)
			(layer "F.SilkS")
		)
		(fp_line
			(start -1.27 3.81)
			(end -1.27 0.7747)
			(stroke
				(width 0.1524)
				(type default)
			)
			(layer "F.SilkS")
		)
		(fp_line
			(start 1.27 -3.81)
			(end 1.27 -3.3147)
			(stroke
				(width 0.1524)
				(type default)
			)
			(layer "F.SilkS")
		)
		(fp_line
			(start 1.27 -1.7653)
			(end 1.27 1.7653)
			(stroke
				(width 0.1524)
				(type default)
			)
			(layer "F.SilkS")
		)
		(fp_line
			(start 1.27 3.3147)
			(end 1.27 3.81)
			(stroke
				(width 0.1524)
				(type default)
			)
			(layer "F.SilkS")
		)
		(fp_line
			(start 1.27 3.81)
			(end -1.27 3.81)
			(stroke
				(width 0.1524)
				(type default)
			)
			(layer "F.SilkS")
		)
		(fp_poly
			(pts
				(xy 4.3942 -3.048) (xy 4.3942 -2.032) (xy 3.3782 -2.54)
			)
			(stroke
				(width 0)
				(type default)
			)
			(fill yes)
			(layer "F.SilkS")
		)
		(fp_line
			(start -1.27 -3.81)
			(end -1.27 3.81)
			(stroke
				(width 0.1)
				(type default)
			)
			(layer "F.Fab")
		)
		(fp_line
			(start -1.27 3.81)
			(end 1.27 3.81)
			(stroke
				(width 0.1)
				(type default)
			)
			(layer "F.Fab")
		)
		(fp_line
			(start 1.27 -3.81)
			(end -1.27 -3.81)
			(stroke
				(width 0.1)
				(type default)
			)
			(layer "F.Fab")
		)
		(fp_line
			(start 1.27 3.81)
			(end 1.27 -3.81)
			(stroke
				(width 0.1)
				(type default)
			)
			(layer "F.Fab")
		)
		(fp_poly
			(pts
				(xy 4.3942 -3.048) (xy 4.3942 -2.032) (xy 3.3782 -2.54)
			)
			(stroke
				(width 0)
				(type default)
			)
			(fill yes)
			(layer "F.Fab")
		)
		(fp_text user "3"
			(at 3.921252 2.54 90)
			(unlocked yes)
			(layer "F.SilkS")
			(effects
				(font
					(size 0.7874 0.5842)
					(thickness 0.1524)
				)
			)
		)
		(fp_text user "3"
			(at 3.921252 2.54 90)
			(unlocked yes)
			(layer "F.Fab")
			(effects
				(font
					(size 0.7874 0.5842)
					(thickness 0.1524)
				)
			)
		)
		(pad "1" smd rect
			(at 1.459992 -2.54 90)
			(size 1.27 3.429)
			(layers "F.Cu" "F.Mask" "F.Paste")
			(net "Net_986")
		)
		(pad "2" smd rect
			(at -1.459992 0 90)
			(size 1.27 3.429)
			(layers "F.Cu" "F.Mask" "F.Paste")
			(net "JP_FPGA_DEBUG_N")
		)
		(pad "3" smd rect
			(at 1.459992 2.54 90)
			(size 1.27 3.429)
			(layers "F.Cu" "F.Mask" "F.Paste")
			(net "GND")
		)
	)
)
